# T6G (Grand Teton) — schematic netlist excerpt (pin names and nets, part order shuffled) for the footprints in the layout excerpt that follows; sources: Cadence DE-HDL packaged netlist, KiCad conversion of 04192023_DAF0TMB3IC0_F0TG_MB_C_brd_V02_OCP.brd

R6180  Q_RES  1K 1% EMPTY  pkg 0402LF  page 112 : A = FM_P2E_BUF2_VOD_SEL ; B = GND
PC156  Q_CAP  0.22UF 16V 10% X7R  pkg 0402  page 205 : A = SW_PVDDIO_P0_BOOT2_R ; B = SW_PVDDIO_P0_BOOTR2

(kicad_pcb
	(version 20260206)
	(generator "pcbnew")
	(generator_version "10.0")
	(general
		(thickness 1.6)
		(legacy_teardrops no)
	)
	(paper "A4")
	(title_block
		(title "04192023_DAF0TMB3IC0_F0TG_MB_C_brd_V02_OCP.brd")
		(comment 1 "Grand Teton / footprints 3050-3051 of 8354")
	)
	(layers
		(0 "F.Cu" signal "TOP")
		(4 "In1.Cu" signal "GND")
		(6 "In2.Cu" signal "IN1")
		(8 "In3.Cu" signal "GND1")
		(10 "In4.Cu" signal "IN2")
		(12 "In5.Cu" signal "GND2")
		(14 "In6.Cu" signal "IN3")
		(16 "In7.Cu" signal "GND3")
		(18 "In8.Cu" signal "VCC")
		(20 "In9.Cu" signal "VCC1")
		(22 "In10.Cu" signal "GND4")
		(24 "In11.Cu" signal "IN4")
		(26 "In12.Cu" signal "GND5")
		(28 "In13.Cu" signal "IN5")
		(30 "In14.Cu" signal "GND6")
		(32 "In15.Cu" signal "IN6")
		(34 "In16.Cu" signal "GND7")
		(2 "B.Cu" signal "BOTTOM")
		(9 "F.Adhes" user "F.Adhesive")
		(11 "B.Adhes" user "B.Adhesive")
		(13 "F.Paste" user "Package Geometry/Pastemask Top")
		(15 "B.Paste" user "Package Geometry/Pastemask Bottom")
		(5 "F.SilkS" user "Ref Des/Silkscreen Top")
		(7 "B.SilkS" user "Ref Des/Silkscreen Bottom")
		(1 "F.Mask" user "Board Geometry/Soldermask Top")
		(3 "B.Mask" user "Board Geometry/Soldermask Bottom")
		(17 "Dwgs.User" user "User.Drawings")
		(19 "Cmts.User" user "User.Comments")
		(21 "Eco1.User" user "User.Eco1")
		(23 "Eco2.User" user "User.Eco2")
		(25 "Edge.Cuts" user "Board Geometry/Outline")
		(27 "Margin" user)
		(31 "F.CrtYd" user "Package Geometry/Place Bound Top")
		(29 "B.CrtYd" user "Package Geometry/Place Bound Bottom")
		(35 "F.Fab" user "Ref Des/Assembly Top")
		(33 "B.Fab" user "Ref Des/Assembly Bottom")
	)
	(footprint ""
		(layer "F.Cu")
		(at 293.79418 -351.368106 -90)
		(property "Reference" "PC156"
			(at 0 0 270)
			(layer "F.SilkS")
			(hide yes)
			(effects
				(font
					(size 1.27 1.27)
				)
			)
		)
		(property "Value" ""
			(at 0 0 270)
			(layer "F.Fab")
			(effects
				(font
					(size 1.27 1.27)
				)
			)
		)
		(duplicate_pad_numbers_are_jumpers no)
		(fp_line
			(start -0.7874 0.4064)
			(end -0.7874 -0.4064)
			(stroke
				(width 0.1524)
				(type default)
			)
			(layer "F.SilkS")
		)
		(fp_line
			(start 0.7874 0.4064)
			(end -0.7874 0.4064)
			(stroke
				(width 0.1524)
				(type default)
			)
			(layer "F.SilkS")
		)
		(fp_line
			(start -0.7874 -0.4064)
			(end 0.7874 -0.4064)
			(stroke
				(width 0.1524)
				(type default)
			)
			(layer "F.SilkS")
		)
		(fp_line
			(start 0.7874 -0.4064)
			(end 0.7874 0.4064)
			(stroke
				(width 0.1524)
				(type default)
			)
			(layer "F.SilkS")
		)
		(fp_line
			(start -0.67945 0.3048)
			(end -0.67945 -0.305054)
			(stroke
				(width 0.1)
				(type default)
			)
			(layer "F.Fab")
		)
		(fp_line
			(start -0.12065 0.3048)
			(end -0.67945 0.3048)
			(stroke
				(width 0.1)
				(type default)
			)
			(layer "F.Fab")
		)
		(fp_line
			(start 0.120396 0.3048)
			(end 0.120396 0.2794)
			(stroke
				(width 0.1)
				(type default)
			)
			(layer "F.Fab")
		)
		(fp_line
			(start 0.67945 0.3048)
			(end 0.120396 0.3048)
			(stroke
				(width 0.1)
				(type default)
			)
			(layer "F.Fab")
		)
		(fp_line
			(start -0.12065 0.2794)
			(end -0.12065 0.3048)
			(stroke
				(width 0.1)
				(type default)
			)
			(layer "F.Fab")
		)
		(fp_line
			(start 0.120396 0.2794)
			(end -0.12065 0.2794)
			(stroke
				(width 0.1)
				(type default)
			)
			(layer "F.Fab")
		)
		(fp_line
			(start -0.12065 -0.2794)
			(end 0.12065 -0.2794)
			(stroke
				(width 0.1)
				(type default)
			)
			(layer "F.Fab")
		)
		(fp_line
			(start 0.12065 -0.2794)
			(end 0.12065 -0.3048)
			(stroke
				(width 0.1)
				(type default)
			)
			(layer "F.Fab")
		)
		(fp_line
			(start 0.12065 -0.3048)
			(end 0.67945 -0.3048)
			(stroke
				(width 0.1)
				(type default)
			)
			(layer "F.Fab")
		)
		(fp_line
			(start 0.67945 -0.3048)
			(end 0.67945 0.3048)
			(stroke
				(width 0.1)
				(type default)
			)
			(layer "F.Fab")
		)
		(fp_line
			(start -0.67945 -0.305054)
			(end -0.12065 -0.305054)
			(stroke
				(width 0.1)
				(type default)
			)
			(layer "F.Fab")
		)
		(fp_line
			(start -0.12065 -0.305054)
			(end -0.12065 -0.2794)
			(stroke
				(width 0.1)
				(type default)
			)
			(layer "F.Fab")
		)
		(pad "1" smd circle
			(at -0.40005 0 270)
			(size 0 0)
			(layers "F.Cu" "F.Mask" "F.Paste")
			(net "SW_PVDDIO_P0_BOOT2_R")
		)
		(pad "2" smd circle
			(at 0.40005 0 270)
			(size 0 0)
			(layers "F.Cu" "F.Mask" "F.Paste")
			(net "SW_PVDDIO_P0_BOOTR2")
		)
	)
	(footprint ""
		(layer "F.Cu")
		(at 17.380458 -418.690298 -90)
		(property "Reference" "R6180"
			(at 0 0 270)
			(layer "F.SilkS")
			(hide yes)
			(effects
				(font
					(size 1.27 1.27)
				)
			)
		)
		(property "Value" ""
			(at 0 0 270)
			(layer "F.Fab")
			(effects
				(font
					(size 1.27 1.27)
				)
			)
		)
		(duplicate_pad_numbers_are_jumpers no)
		(fp_line
			(start -0.7874 0.4064)
			(end -0.7874 -0.4064)
			(stroke
				(width 0.1524)
				(type default)
			)
			(layer "F.SilkS")
		)
		(fp_line
			(start 0.7874 0.4064)
			(end -0.7874 0.4064)
			(stroke
				(width 0.1524)
				(type default)
			)
			(layer "F.SilkS")
		)
		(fp_line
			(start -0.7874 -0.4064)
			(end 0.7874 -0.4064)
			(stroke
				(width 0.1524)
				(type default)
			)
			(layer "F.SilkS")
		)
		(fp_line
			(start 0.7874 -0.4064)
			(end 0.7874 0.4064)
			(stroke
				(width 0.1524)
				(type default)
			)
			(layer "F.SilkS")
		)
		(fp_line
			(start -0.67945 0.3048)
			(end -0.67945 -0.305054)
			(stroke
				(width 0.1)
				(type default)
			)
			(layer "F.Fab")
		)
		(fp_line
			(start -0.12065 0.3048)
			(end -0.67945 0.3048)
			(stroke
				(width 0.1)
				(type default)
			)
			(layer "F.Fab")
		)
		(fp_line
			(start 0.120396 0.3048)
			(end 0.120396 0.2794)
			(stroke
				(width 0.1)
				(type default)
			)
			(layer "F.Fab")
		)
		(fp_line
			(start 0.67945 0.3048)
			(end 0.120396 0.3048)
			(stroke
				(width 0.1)
				(type default)
			)
			(layer "F.Fab")
		)
		(fp_line
			(start -0.12065 0.2794)
			(end -0.12065 0.3048)
			(stroke
				(width 0.1)
				(type default)
			)
			(layer "F.Fab")
		)
		(fp_line
			(start 0.120396 0.2794)
			(end -0.12065 0.2794)
			(stroke
				(width 0.1)
				(type default)
			)
			(layer "F.Fab")
		)
		(fp_line
			(start -0.12065 -0.2794)
			(end 0.12065 -0.2794)
			(stroke
				(width 0.1)
				(type default)
			)
			(layer "F.Fab")
		)
		(fp_line
			(start 0.12065 -0.2794)
			(end 0.12065 -0.3048)
			(stroke
				(width 0.1)
				(type default)
			)
			(layer "F.Fab")
		)
		(fp_line
			(start 0.12065 -0.3048)
			(end 0.67945 -0.3048)
			(stroke
				(width 0.1)
				(type default)
			)
			(layer "F.Fab")
		)
		(fp_line
			(start 0.67945 -0.3048)
			(end 0.67945 0.3048)
			(stroke
				(width 0.1)
				(type default)
			)
			(layer "F.Fab")
		)
		(fp_line
			(start -0.67945 -0.305054)
			(end -0.12065 -0.305054)
			(stroke
				(width 0.1)
				(type default)
			)
			(layer "F.Fab")
		)
		(fp_line
			(start -0.12065 -0.305054)
			(end -0.12065 -0.2794)
			(stroke
				(width 0.1)
				(type default)
			)
			(layer "F.Fab")
		)
		(pad "1" smd circle
			(at -0.40005 0 270)
			(size 0 0)
			(layers "F.Cu" "F.Mask" "F.Paste")
			(net "FM_P2E_BUF2_VOD_SEL")
		)
		(pad "2" smd circle
			(at 0.40005 0 270)
			(size 0 0)
			(layers "F.Cu" "F.Mask" "F.Paste")
			(net "GND")
		)
	)
)
